# S9S_MB_2U (Grand Teton) — schematic netlist excerpt (pin names and nets, part order shuffled) for the footprints in the layout excerpt that follows; sources: Cadence DE-HDL packaged netlist, KiCad conversion of 03242023_DA0F0TMBIJ0_F0T_Motherboard_J_brd_V01_OCP.brd

C1507  Q_CAP  18PF 50V 5% C0G  pkg 0402  page 179 : A = XTAL_PCH_RTC2_R ; B = GND
R3034  Q_RES  4.7K 5% CHIP  pkg 0402LF  page 148 : A = P3V3_AUX ; B = FM_SMB_2_ALERT_GPU
PC1203  Q_CAPP  560UF 2.5V 20% OSCON  pkg THLF  page 290 : A = PVCCFA_EHV_FIVRA_CPU1 ; B = GND

(kicad_pcb
	(version 20260206)
	(generator "pcbnew")
	(generator_version "10.0")
	(general
		(thickness 1.6)
		(legacy_teardrops no)
	)
	(paper "A4")
	(title_block
		(title "03242023_DA0F0TMBIJ0_F0T_Motherboard_J_brd_V01_OCP.brd")
		(comment 1 "Grand Teton / footprints 1411-1413 of 6105")
	)
	(layers
		(0 "F.Cu" signal "TOP")
		(4 "In1.Cu" signal "GND")
		(6 "In2.Cu" signal "IN1")
		(8 "In3.Cu" signal "GND1")
		(10 "In4.Cu" signal "IN2")
		(12 "In5.Cu" signal "GND2")
		(14 "In6.Cu" signal "IN3")
		(16 "In7.Cu" signal "GND3")
		(18 "In8.Cu" signal "VCC")
		(20 "In9.Cu" signal "VCC1")
		(22 "In10.Cu" signal "GND4")
		(24 "In11.Cu" signal "IN4")
		(26 "In12.Cu" signal "GND5")
		(28 "In13.Cu" signal "IN5")
		(30 "In14.Cu" signal "GND6")
		(32 "In15.Cu" signal "IN6")
		(34 "In16.Cu" signal "GND7")
		(2 "B.Cu" signal "BOTTOM")
		(9 "F.Adhes" user "F.Adhesive")
		(11 "B.Adhes" user "B.Adhesive")
		(13 "F.Paste" user "Package Geometry/Pastemask Top")
		(15 "B.Paste" user "Package Geometry/Pastemask Bottom")
		(5 "F.SilkS" user "Ref Des/Silkscreen Top")
		(7 "B.SilkS" user "Ref Des/Silkscreen Bottom")
		(1 "F.Mask" user "Board Geometry/Soldermask Top")
		(3 "B.Mask" user "Board Geometry/Soldermask Bottom")
		(17 "Dwgs.User" user "User.Drawings")
		(19 "Cmts.User" user "User.Comments")
		(21 "Eco1.User" user "User.Eco1")
		(23 "Eco2.User" user "User.Eco2")
		(25 "Edge.Cuts" user "Board Geometry/Outline")
		(27 "Margin" user)
		(31 "F.CrtYd" user "Package Geometry/Place Bound Top")
		(29 "B.CrtYd" user "Package Geometry/Place Bound Bottom")
		(35 "F.Fab" user "Ref Des/Assembly Top")
		(33 "B.Fab" user "Ref Des/Assembly Bottom")
	)
	(footprint ""
		(layer "F.Cu")
		(at 326.323198 -32.688022 -45)
		(property "Reference" "C1507"
			(at 0 0 315)
			(layer "F.SilkS")
			(hide yes)
			(effects
				(font
					(size 1.27 1.27)
				)
			)
		)
		(property "Value" ""
			(at 0 0 315)
			(layer "F.Fab")
			(effects
				(font
					(size 1.27 1.27)
				)
			)
		)
		(duplicate_pad_numbers_are_jumpers no)
		(fp_line
			(start -0.787389 0.406267)
			(end -0.787389 -0.406267)
			(stroke
				(width 0.1524)
				(type default)
			)
			(layer "F.SilkS")
		)
		(fp_line
			(start -0.787389 -0.406267)
			(end 0.787389 -0.406267)
			(stroke
				(width 0.1524)
				(type default)
			)
			(layer "F.SilkS")
		)
		(fp_line
			(start 0.787389 0.406267)
			(end -0.787389 0.406267)
			(stroke
				(width 0.1524)
				(type default)
			)
			(layer "F.SilkS")
		)
		(fp_line
			(start 0.787389 -0.406267)
			(end 0.787389 0.406267)
			(stroke
				(width 0.1524)
				(type default)
			)
			(layer "F.SilkS")
		)
		(fp_line
			(start -0.679446 0.30479)
			(end -0.679446 -0.305149)
			(stroke
				(width 0.1)
				(type default)
			)
			(layer "F.Fab")
		)
		(fp_line
			(start -0.120515 0.30479)
			(end -0.679446 0.30479)
			(stroke
				(width 0.1)
				(type default)
			)
			(layer "F.Fab")
		)
		(fp_line
			(start -0.120695 0.279466)
			(end -0.120515 0.30479)
			(stroke
				(width 0.1)
				(type default)
			)
			(layer "F.Fab")
		)
		(fp_line
			(start -0.679446 -0.305149)
			(end -0.120695 -0.304969)
			(stroke
				(width 0.1)
				(type default)
			)
			(layer "F.Fab")
		)
		(fp_line
			(start 0.120515 0.30479)
			(end 0.120335 0.279466)
			(stroke
				(width 0.1)
				(type default)
			)
			(layer "F.Fab")
		)
		(fp_line
			(start 0.120335 0.279466)
			(end -0.120695 0.279466)
			(stroke
				(width 0.1)
				(type default)
			)
			(layer "F.Fab")
		)
		(fp_line
			(start -0.120695 -0.279466)
			(end 0.120695 -0.279466)
			(stroke
				(width 0.1)
				(type default)
			)
			(layer "F.Fab")
		)
		(fp_line
			(start -0.120695 -0.304969)
			(end -0.120695 -0.279466)
			(stroke
				(width 0.1)
				(type default)
			)
			(layer "F.Fab")
		)
		(fp_line
			(start 0.679446 0.30479)
			(end 0.120515 0.30479)
			(stroke
				(width 0.1)
				(type default)
			)
			(layer "F.Fab")
		)
		(fp_line
			(start 0.120695 -0.279466)
			(end 0.120515 -0.30479)
			(stroke
				(width 0.1)
				(type default)
			)
			(layer "F.Fab")
		)
		(fp_line
			(start 0.120515 -0.30479)
			(end 0.679446 -0.30479)
			(stroke
				(width 0.1)
				(type default)
			)
			(layer "F.Fab")
		)
		(fp_line
			(start 0.679446 -0.30479)
			(end 0.679446 0.30479)
			(stroke
				(width 0.1)
				(type default)
			)
			(layer "F.Fab")
		)
		(pad "1" smd circle
			(at -0.40005 0 315)
			(size 0 0)
			(layers "F.Cu" "F.Mask" "F.Paste")
			(net "XTAL_PCH_RTC2_R")
		)
		(pad "2" smd circle
			(at 0.40005 0 315)
			(size 0 0)
			(layers "F.Cu" "F.Mask" "F.Paste")
			(net "GND")
		)
	)
	(footprint ""
		(layer "F.Cu")
		(at 114.81308 -393.048998 180)
		(property "Reference" "R3034"
			(at 0 0 180)
			(layer "F.SilkS")
			(hide yes)
			(effects
				(font
					(size 1.27 1.27)
				)
			)
		)
		(property "Value" ""
			(at 0 0 180)
			(layer "F.Fab")
			(effects
				(font
					(size 1.27 1.27)
				)
			)
		)
		(duplicate_pad_numbers_are_jumpers no)
		(fp_line
			(start 0.7874 0.4064)
			(end -0.7874 0.4064)
			(stroke
				(width 0.1524)
				(type default)
			)
			(layer "F.SilkS")
		)
		(fp_line
			(start 0.7874 -0.4064)
			(end 0.7874 0.4064)
			(stroke
				(width 0.1524)
				(type default)
			)
			(layer "F.SilkS")
		)
		(fp_line
			(start -0.7874 0.4064)
			(end -0.7874 -0.4064)
			(stroke
				(width 0.1524)
				(type default)
			)
			(layer "F.SilkS")
		)
		(fp_line
			(start -0.7874 -0.4064)
			(end 0.7874 -0.4064)
			(stroke
				(width 0.1524)
				(type default)
			)
			(layer "F.SilkS")
		)
		(fp_line
			(start 0.67945 0.3048)
			(end 0.120396 0.3048)
			(stroke
				(width 0.1)
				(type default)
			)
			(layer "F.Fab")
		)
		(fp_line
			(start 0.67945 -0.3048)
			(end 0.67945 0.3048)
			(stroke
				(width 0.1)
				(type default)
			)
			(layer "F.Fab")
		)
		(fp_line
			(start 0.12065 -0.2794)
			(end 0.12065 -0.3048)
			(stroke
				(width 0.1)
				(type default)
			)
			(layer "F.Fab")
		)
		(fp_line
			(start 0.12065 -0.3048)
			(end 0.67945 -0.3048)
			(stroke
				(width 0.1)
				(type default)
			)
			(layer "F.Fab")
		)
		(fp_line
			(start 0.120396 0.3048)
			(end 0.120396 0.2794)
			(stroke
				(width 0.1)
				(type default)
			)
			(layer "F.Fab")
		)
		(fp_line
			(start 0.120396 0.2794)
			(end -0.12065 0.2794)
			(stroke
				(width 0.1)
				(type default)
			)
			(layer "F.Fab")
		)
		(fp_line
			(start -0.12065 0.3048)
			(end -0.67945 0.3048)
			(stroke
				(width 0.1)
				(type default)
			)
			(layer "F.Fab")
		)
		(fp_line
			(start -0.12065 0.2794)
			(end -0.12065 0.3048)
			(stroke
				(width 0.1)
				(type default)
			)
			(layer "F.Fab")
		)
		(fp_line
			(start -0.12065 -0.2794)
			(end 0.12065 -0.2794)
			(stroke
				(width 0.1)
				(type default)
			)
			(layer "F.Fab")
		)
		(fp_line
			(start -0.12065 -0.305054)
			(end -0.12065 -0.2794)
			(stroke
				(width 0.1)
				(type default)
			)
			(layer "F.Fab")
		)
		(fp_line
			(start -0.67945 0.3048)
			(end -0.67945 -0.305054)
			(stroke
				(width 0.1)
				(type default)
			)
			(layer "F.Fab")
		)
		(fp_line
			(start -0.67945 -0.305054)
			(end -0.12065 -0.305054)
			(stroke
				(width 0.1)
				(type default)
			)
			(layer "F.Fab")
		)
		(pad "1" smd circle
			(at -0.40005 0 180)
			(size 0 0)
			(layers "F.Cu" "F.Mask" "F.Paste")
			(net "P3V3_AUX")
		)
		(pad "2" smd circle
			(at 0.40005 0 180)
			(size 0 0)
			(layers "F.Cu" "F.Mask" "F.Paste")
			(net "FM_SMB_2_ALERT_GPU")
		)
	)
	(footprint ""
		(layer "F.Cu")
		(at 170.965622 -337.477608)
		(property "Reference" "PC1203"
			(at 0 0 0)
			(layer "F.SilkS")
			(hide yes)
			(effects
				(font
					(size 1.27 1.27)
				)
			)
		)
		(property "Value" ""
			(at 0 0 0)
			(layer "F.Fab")
			(effects
				(font
					(size 1.27 1.27)
				)
			)
		)
		(duplicate_pad_numbers_are_jumpers no)
		(fp_line
			(start 2.750058 0.999998)
			(end -2.750058 0.999998)
			(stroke
				(width 0.1524)
				(type default)
			)
			(layer "F.SilkS")
		)
		(fp_circle
			(center 0 0.999998)
			(end 2.750058 0.999998)
			(stroke
				(width 0.1524)
				(type default)
			)
			(fill no)
			(layer "F.SilkS")
		)
		(fp_poly
			(pts
				(arc
					(start 2.750058 0.999998)
					(mid 0 3.750056)
					(end -2.750058 0.999998)
				)
			)
			(stroke
				(width 0)
				(type default)
			)
			(fill yes)
			(layer "F.SilkS")
		)
		(fp_circle
			(center 0 0.999998)
			(end 2.750058 0.999998)
			(stroke
				(width 0.1)
				(type default)
			)
			(fill no)
			(layer "F.Fab")
		)
		(pad "1" thru_hole rect
			(at 0 0)
			(size 1.5748 1.5748)
			(drill 1.0668)
			(layers "*.Cu" "*.Mask")
			(remove_unused_layers no)
			(net "PVCCFA_EHV_FIVRA_CPU1")
			(clearance 0)
			(padstack
				(mode front_inner_back)
				(layer "Inner"
					(shape circle)
					(size 1.5748 1.5748)
					(clearance 0)
				)
				(layer "B.Cu"
					(shape rect)
					(size 1.5748 1.5748)
					(clearance 0)
				)
			)
		)
		(pad "2" thru_hole circle
			(at 0 1.999996)
			(size 1.5748 1.5748)
			(drill 1.0668)
			(layers "*.Cu" "*.Mask")
			(remove_unused_layers no)
			(net "GND")
			(clearance 0)
		)
	)
)
